# SCM (Grand Teton) — schematic netlist excerpt (pin names and nets, part order shuffled) for the footprints in the layout excerpt that follows; sources: Cadence DE-HDL packaged netlist, KiCad conversion of 12092022_DA0F0TMDCD0_F0T_Management_Board_D_brd_V3_OCP.brd

R339  Q_RES  120 1% CHIP  pkg 0402LF  page 20 : A = GND ; B = M_BMC_DDR4_MA<13>

U6  74LVC2G07DW7  74LVC2G07DW-7 IC  pkg SOT363_0-65_2X1-25XC  page 22
  \1a\  = PWRGD_P1V0_AUX_DELAY
  GND  = GND
  \2a\  = RST_SRST_PLD_BMC_R1_N
  \2y\  = RST_SRST_PLD_BMC_BUF_N
  VCC  = P3V3_AUX
  \1y\  = PWRGD_P1V0_AUX_DELAY_BUF

(kicad_pcb
	(version 20260206)
	(generator "pcbnew")
	(generator_version "10.0")
	(general
		(thickness 1.6)
		(legacy_teardrops no)
	)
	(paper "A4")
	(title_block
		(title "12092022_DA0F0TMDCD0_F0T_Management_Board_D_brd_V3_OCP.brd")
		(comment 1 "Grand Teton / footprints 475-476 of 1440")
	)
	(layers
		(0 "F.Cu" signal "TOP")
		(4 "In1.Cu" signal "GND")
		(6 "In2.Cu" signal "IN1")
		(8 "In3.Cu" signal "GND1")
		(10 "In4.Cu" signal "IN2")
		(12 "In5.Cu" signal "VCC")
		(14 "In6.Cu" signal "VCC1")
		(16 "In7.Cu" signal "IN3")
		(18 "In8.Cu" signal "GND2")
		(20 "In9.Cu" signal "IN4")
		(22 "In10.Cu" signal "GND3")
		(2 "B.Cu" signal "BOTTOM")
		(9 "F.Adhes" user "F.Adhesive")
		(11 "B.Adhes" user "B.Adhesive")
		(13 "F.Paste" user "Package Geometry/Pastemask Top")
		(15 "B.Paste" user "Package Geometry/Pastemask Bottom")
		(5 "F.SilkS" user "Ref Des/Silkscreen Top")
		(7 "B.SilkS" user "Ref Des/Silkscreen Bottom")
		(1 "F.Mask" user "Board Geometry/Soldermask Top")
		(3 "B.Mask" user "Board Geometry/Soldermask Bottom")
		(17 "Dwgs.User" user "User.Drawings")
		(19 "Cmts.User" user "User.Comments")
		(21 "Eco1.User" user "User.Eco1")
		(23 "Eco2.User" user "User.Eco2")
		(25 "Edge.Cuts" user "Board Geometry/Outline")
		(27 "Margin" user)
		(31 "F.CrtYd" user "Package Geometry/Place Bound Top")
		(29 "B.CrtYd" user "Package Geometry/Place Bound Bottom")
		(35 "F.Fab" user "Ref Des/Assembly Top")
		(33 "B.Fab" user "Ref Des/Assembly Bottom")
	)
	(footprint ""
		(layer "F.Cu")
		(at 8.128 -82.55)
		(property "Reference" "U6"
			(at 2.45237 0.3048 90)
			(unlocked yes)
			(layer "F.SilkS")
			(effects
				(font
					(size 0.7874 0.5842)
					(thickness 0.1524)
				)
				(justify left)
			)
		)
		(property "Value" ""
			(at 0 0 0)
			(layer "F.Fab")
			(effects
				(font
					(size 1.27 1.27)
				)
			)
		)
		(duplicate_pad_numbers_are_jumpers no)
		(fp_line
			(start -1.38176 -1.100074)
			(end -1.38176 1.100074)
			(stroke
				(width 0.1524)
				(type default)
			)
			(layer "F.SilkS")
		)
		(fp_line
			(start -1.38176 1.100074)
			(end 1.38176 1.100074)
			(stroke
				(width 0.1524)
				(type default)
			)
			(layer "F.SilkS")
		)
		(fp_line
			(start -0.592074 -1.100074)
			(end -1.38176 -1.100074)
			(stroke
				(width 0.1524)
				(type default)
			)
			(layer "F.SilkS")
		)
		(fp_line
			(start 0 -0.508)
			(end -0.592074 -1.100074)
			(stroke
				(width 0.1524)
				(type default)
			)
			(layer "F.SilkS")
		)
		(fp_line
			(start 0.592074 -1.100074)
			(end 0 -0.508)
			(stroke
				(width 0.1524)
				(type default)
			)
			(layer "F.SilkS")
		)
		(fp_line
			(start 1.38176 -1.100074)
			(end 0.592074 -1.100074)
			(stroke
				(width 0.1524)
				(type default)
			)
			(layer "F.SilkS")
		)
		(fp_line
			(start 1.38176 1.100074)
			(end 1.38176 -1.100074)
			(stroke
				(width 0.1524)
				(type default)
			)
			(layer "F.SilkS")
		)
		(fp_poly
			(pts
				(xy -1.9431 -0.870204) (xy -1.50241 -0.649986) (xy -1.9431 -0.429768)
			)
			(stroke
				(width 0)
				(type default)
			)
			(fill yes)
			(layer "F.SilkS")
		)
		(fp_line
			(start -0.674878 -1.100074)
			(end -0.674878 1.100074)
			(stroke
				(width 0.1)
				(type default)
			)
			(layer "F.Fab")
		)
		(fp_line
			(start -0.674878 1.100074)
			(end 0.674878 1.100074)
			(stroke
				(width 0.1)
				(type default)
			)
			(layer "F.Fab")
		)
		(fp_line
			(start 0.674878 -1.100074)
			(end -0.674878 -1.100074)
			(stroke
				(width 0.1)
				(type default)
			)
			(layer "F.Fab")
		)
		(fp_line
			(start 0.674878 1.100074)
			(end 0.674878 -1.100074)
			(stroke
				(width 0.1)
				(type default)
			)
			(layer "F.Fab")
		)
		(fp_poly
			(pts
				(xy -1.9431 -0.870204) (xy -1.50241 -0.649986) (xy -1.9431 -0.429768)
			)
			(stroke
				(width 0)
				(type default)
			)
			(fill yes)
			(layer "F.Fab")
		)
		(pad "1" smd rect
			(at -0.94996 -0.649986 270)
			(size 0.4318 0.6096)
			(layers "F.Cu" "F.Mask" "F.Paste")
			(net "PWRGD_P1V0_AUX_DELAY")
		)
		(pad "2" smd rect
			(at -0.94996 0 270)
			(size 0.4318 0.6096)
			(layers "F.Cu" "F.Mask" "F.Paste")
			(net "GND")
		)
		(pad "3" smd rect
			(at -0.94996 0.649986 270)
			(size 0.4318 0.6096)
			(layers "F.Cu" "F.Mask" "F.Paste")
			(net "RST_SRST_PLD_BMC_R1_N")
		)
		(pad "4" smd rect
			(at 0.94996 0.649986 270)
			(size 0.4318 0.6096)
			(layers "F.Cu" "F.Mask" "F.Paste")
			(net "RST_SRST_PLD_BMC_BUF_N")
		)
		(pad "5" smd rect
			(at 0.94996 0 270)
			(size 0.4318 0.6096)
			(layers "F.Cu" "F.Mask" "F.Paste")
			(net "P3V3_AUX")
		)
		(pad "6" smd rect
			(at 0.94996 -0.649986 270)
			(size 0.4318 0.6096)
			(layers "F.Cu" "F.Mask" "F.Paste")
			(net "PWRGD_P1V0_AUX_DELAY_BUF")
		)
	)
	(footprint ""
		(layer "F.Cu")
		(at 85.29955 -41.887394 180)
		(property "Reference" "R339"
			(at 0 0 180)
			(layer "F.SilkS")
			(hide yes)
			(effects
				(font
					(size 1.27 1.27)
				)
			)
		)
		(property "Value" ""
			(at 0 0 180)
			(layer "F.Fab")
			(effects
				(font
					(size 1.27 1.27)
				)
			)
		)
		(duplicate_pad_numbers_are_jumpers no)
		(fp_line
			(start 0.7874 0.4064)
			(end -0.7874 0.4064)
			(stroke
				(width 0.1524)
				(type default)
			)
			(layer "F.SilkS")
		)
		(fp_line
			(start 0.7874 -0.4064)
			(end 0.7874 0.4064)
			(stroke
				(width 0.1524)
				(type default)
			)
			(layer "F.SilkS")
		)
		(fp_line
			(start -0.7874 0.4064)
			(end -0.7874 -0.4064)
			(stroke
				(width 0.1524)
				(type default)
			)
			(layer "F.SilkS")
		)
		(fp_line
			(start -0.7874 -0.4064)
			(end 0.7874 -0.4064)
			(stroke
				(width 0.1524)
				(type default)
			)
			(layer "F.SilkS")
		)
		(fp_line
			(start 0.67945 0.3048)
			(end 0.120396 0.3048)
			(stroke
				(width 0.1)
				(type default)
			)
			(layer "F.Fab")
		)
		(fp_line
			(start 0.67945 -0.3048)
			(end 0.67945 0.3048)
			(stroke
				(width 0.1)
				(type default)
			)
			(layer "F.Fab")
		)
		(fp_line
			(start 0.12065 -0.2794)
			(end 0.12065 -0.3048)
			(stroke
				(width 0.1)
				(type default)
			)
			(layer "F.Fab")
		)
		(fp_line
			(start 0.12065 -0.3048)
			(end 0.67945 -0.3048)
			(stroke
				(width 0.1)
				(type default)
			)
			(layer "F.Fab")
		)
		(fp_line
			(start 0.120396 0.3048)
			(end 0.120396 0.2794)
			(stroke
				(width 0.1)
				(type default)
			)
			(layer "F.Fab")
		)
		(fp_line
			(start 0.120396 0.2794)
			(end -0.12065 0.2794)
			(stroke
				(width 0.1)
				(type default)
			)
			(layer "F.Fab")
		)
		(fp_line
			(start -0.12065 0.3048)
			(end -0.67945 0.3048)
			(stroke
				(width 0.1)
				(type default)
			)
			(layer "F.Fab")
		)
		(fp_line
			(start -0.12065 0.2794)
			(end -0.12065 0.3048)
			(stroke
				(width 0.1)
				(type default)
			)
			(layer "F.Fab")
		)
		(fp_line
			(start -0.12065 -0.2794)
			(end 0.12065 -0.2794)
			(stroke
				(width 0.1)
				(type default)
			)
			(layer "F.Fab")
		)
		(fp_line
			(start -0.12065 -0.305054)
			(end -0.12065 -0.2794)
			(stroke
				(width 0.1)
				(type default)
			)
			(layer "F.Fab")
		)
		(fp_line
			(start -0.67945 0.3048)
			(end -0.67945 -0.305054)
			(stroke
				(width 0.1)
				(type default)
			)
			(layer "F.Fab")
		)
		(fp_line
			(start -0.67945 -0.305054)
			(end -0.12065 -0.305054)
			(stroke
				(width 0.1)
				(type default)
			)
			(layer "F.Fab")
		)
		(pad "1" smd circle
			(at -0.40005 0 180)
			(size 0 0)
			(layers "F.Cu" "F.Mask" "F.Paste")
			(net "GND")
		)
		(pad "2" smd circle
			(at 0.40005 0 180)
			(size 0 0)
			(layers "F.Cu" "F.Mask" "F.Paste")
			(net "M_BMC_DDR4_MA<13>")
		)
	)
)
